(kicad_pcb
	(version 20260206)
	(generator "pcbnew")
	(generator_version "10.0")
	(general
		(thickness 1.6)
		(legacy_teardrops no)
	)
	(paper "A4")
	(title_block
		(title "12092022_DA0F0TMDCD0_F0T_Management_Board_D_brd_V3_OCP.brd")
		(comment 1 "Grand Teton / footprints 250-256 of 1440")
	)
	(layers
		(0 "F.Cu" signal "TOP")
		(4 "In1.Cu" signal "GND")
		(6 "In2.Cu" signal "IN1")
		(8 "In3.Cu" signal "GND1")
		(10 "In4.Cu" signal "IN2")
		(12 "In5.Cu" signal "VCC")
		(14 "In6.Cu" signal "VCC1")
		(16 "In7.Cu" signal "IN3")
		(18 "In8.Cu" signal "GND2")
		(20 "In9.Cu" signal "IN4")
		(22 "In10.Cu" signal "GND3")
		(2 "B.Cu" signal "BOTTOM")
		(9 "F.Adhes" user "F.Adhesive")
		(11 "B.Adhes" user "B.Adhesive")
		(13 "F.Paste" user "Package Geometry/Pastemask Top")
		(15 "B.Paste" user "Package Geometry/Pastemask Bottom")
		(5 "F.SilkS" user "Ref Des/Silkscreen Top")
		(7 "B.SilkS" user "Ref Des/Silkscreen Bottom")
		(1 "F.Mask" user "Board Geometry/Soldermask Top")
		(3 "B.Mask" user "Board Geometry/Soldermask Bottom")
		(17 "Dwgs.User" user "User.Drawings")
		(19 "Cmts.User" user "User.Comments")
		(21 "Eco1.User" user "User.Eco1")
		(23 "Eco2.User" user "User.Eco2")
		(25 "Edge.Cuts" user "Board Geometry/Outline")
		(27 "Margin" user)
		(31 "F.CrtYd" user "Package Geometry/Place Bound Top")
		(29 "B.CrtYd" user "Package Geometry/Place Bound Bottom")
		(35 "F.Fab" user "Ref Des/Assembly Top")
		(33 "B.Fab" user "Ref Des/Assembly Bottom")
	)
	(footprint ""
		(layer "F.Cu")
		(at 29.464 -31.369 180)
		(property "Reference" "R88"
			(at 0 0 180)
			(layer "F.SilkS")
			(hide yes)
			(effects
				(font
					(size 1.27 1.27)
				)
			)
		)
		(property "Value" ""
			(at 0 0 180)
			(layer "F.Fab")
			(effects
				(font
					(size 1.27 1.27)
				)
			)
		)
		(duplicate_pad_numbers_are_jumpers no)
		(fp_line
			(start 0.7874 0.4064)
			(end -0.7874 0.4064)
			(stroke
				(width 0.1524)
				(type default)
			)
			(layer "F.SilkS")
		)
		(fp_line
			(start 0.7874 -0.4064)
			(end 0.7874 0.4064)
			(stroke
				(width 0.1524)
				(type default)
			)
			(layer "F.SilkS")
		)
		(fp_line
			(start -0.7874 0.4064)
			(end -0.7874 -0.4064)
			(stroke
				(width 0.1524)
				(type default)
			)
			(layer "F.SilkS")
		)
		(fp_line
			(start -0.7874 -0.4064)
			(end 0.7874 -0.4064)
			(stroke
				(width 0.1524)
				(type default)
			)
			(layer "F.SilkS")
		)
		(fp_line
			(start 0.67945 0.3048)
			(end 0.120396 0.3048)
			(stroke
				(width 0.1)
				(type default)
			)
			(layer "F.Fab")
		)
		(fp_line
			(start 0.67945 -0.3048)
			(end 0.67945 0.3048)
			(stroke
				(width 0.1)
				(type default)
			)
			(layer "F.Fab")
		)
		(fp_line
			(start 0.12065 -0.2794)
			(end 0.12065 -0.3048)
			(stroke
				(width 0.1)
				(type default)
			)
			(layer "F.Fab")
		)
		(fp_line
			(start 0.12065 -0.3048)
			(end 0.67945 -0.3048)
			(stroke
				(width 0.1)
				(type default)
			)
			(layer "F.Fab")
		)
		(fp_line
			(start 0.120396 0.3048)
			(end 0.120396 0.2794)
			(stroke
				(width 0.1)
				(type default)
			)
			(layer "F.Fab")
		)
		(fp_line
			(start 0.120396 0.2794)
			(end -0.12065 0.2794)
			(stroke
				(width 0.1)
				(type default)
			)
			(layer "F.Fab")
		)
		(fp_line
			(start -0.12065 0.3048)
			(end -0.67945 0.3048)
			(stroke
				(width 0.1)
				(type default)
			)
			(layer "F.Fab")
		)
		(fp_line
			(start -0.12065 0.2794)
			(end -0.12065 0.3048)
			(stroke
				(width 0.1)
				(type default)
			)
			(layer "F.Fab")
		)
		(fp_line
			(start -0.12065 -0.2794)
			(end 0.12065 -0.2794)
			(stroke
				(width 0.1)
				(type default)
			)
			(layer "F.Fab")
		)
		(fp_line
			(start -0.12065 -0.305054)
			(end -0.12065 -0.2794)
			(stroke
				(width 0.1)
				(type default)
			)
			(layer "F.Fab")
		)
		(fp_line
			(start -0.67945 0.3048)
			(end -0.67945 -0.305054)
			(stroke
				(width 0.1)
				(type default)
			)
			(layer "F.Fab")
		)
		(fp_line
			(start -0.67945 -0.305054)
			(end -0.12065 -0.305054)
			(stroke
				(width 0.1)
				(type default)
			)
			(layer "F.Fab")
		)
		(pad "1" smd circle
			(at -0.40005 0 180)
			(size 0 0)
			(layers "F.Cu" "F.Mask" "F.Paste")
			(net "V_DACG_IO")
		)
		(pad "2" smd circle
			(at 0.40005 0 180)
			(size 0 0)
			(layers "F.Cu" "F.Mask" "F.Paste")
			(net "GND")
		)
	)
	(footprint ""
		(layer "F.Cu")
		(at 28.321 -68.453 90)
		(property "Reference" "R850"
			(at 0 0 90)
			(layer "F.SilkS")
			(hide yes)
			(effects
				(font
					(size 1.27 1.27)
				)
			)
		)
		(property "Value" ""
			(at 0 0 90)
			(layer "F.Fab")
			(effects
				(font
					(size 1.27 1.27)
				)
			)
		)
		(duplicate_pad_numbers_are_jumpers no)
		(fp_line
			(start 0.7874 -0.4064)
			(end 0.7874 0.4064)
			(stroke
				(width 0.1524)
				(type default)
			)
			(layer "F.SilkS")
		)
		(fp_line
			(start -0.7874 -0.4064)
			(end 0.7874 -0.4064)
			(stroke
				(width 0.1524)
				(type default)
			)
			(layer "F.SilkS")
		)
		(fp_line
			(start 0.7874 0.4064)
			(end -0.7874 0.4064)
			(stroke
				(width 0.1524)
				(type default)
			)
			(layer "F.SilkS")
		)
		(fp_line
			(start -0.7874 0.4064)
			(end -0.7874 -0.4064)
			(stroke
				(width 0.1524)
				(type default)
			)
			(layer "F.SilkS")
		)
		(fp_line
			(start -0.12065 -0.305054)
			(end -0.12065 -0.2794)
			(stroke
				(width 0.1)
				(type default)
			)
			(layer "F.Fab")
		)
		(fp_line
			(start -0.67945 -0.305054)
			(end -0.12065 -0.305054)
			(stroke
				(width 0.1)
				(type default)
			)
			(layer "F.Fab")
		)
		(fp_line
			(start 0.67945 -0.3048)
			(end 0.67945 0.3048)
			(stroke
				(width 0.1)
				(type default)
			)
			(layer "F.Fab")
		)
		(fp_line
			(start 0.12065 -0.3048)
			(end 0.67945 -0.3048)
			(stroke
				(width 0.1)
				(type default)
			)
			(layer "F.Fab")
		)
		(fp_line
			(start 0.12065 -0.2794)
			(end 0.12065 -0.3048)
			(stroke
				(width 0.1)
				(type default)
			)
			(layer "F.Fab")
		)
		(fp_line
			(start -0.12065 -0.2794)
			(end 0.12065 -0.2794)
			(stroke
				(width 0.1)
				(type default)
			)
			(layer "F.Fab")
		)
		(fp_line
			(start 0.120396 0.2794)
			(end -0.12065 0.2794)
			(stroke
				(width 0.1)
				(type default)
			)
			(layer "F.Fab")
		)
		(fp_line
			(start -0.12065 0.2794)
			(end -0.12065 0.3048)
			(stroke
				(width 0.1)
				(type default)
			)
			(layer "F.Fab")
		)
		(fp_line
			(start 0.67945 0.3048)
			(end 0.120396 0.3048)
			(stroke
				(width 0.1)
				(type default)
			)
			(layer "F.Fab")
		)
		(fp_line
			(start 0.120396 0.3048)
			(end 0.120396 0.2794)
			(stroke
				(width 0.1)
				(type default)
			)
			(layer "F.Fab")
		)
		(fp_line
			(start -0.12065 0.3048)
			(end -0.67945 0.3048)
			(stroke
				(width 0.1)
				(type default)
			)
			(layer "F.Fab")
		)
		(fp_line
			(start -0.67945 0.3048)
			(end -0.67945 -0.305054)
			(stroke
				(width 0.1)
				(type default)
			)
			(layer "F.Fab")
		)
		(pad "1" smd circle
			(at -0.40005 0 90)
			(size 0 0)
			(layers "F.Cu" "F.Mask" "F.Paste")
			(net "SMB_BMC_MM16_R5_SDA")
		)
		(pad "2" smd circle
			(at 0.40005 0 90)
			(size 0 0)
			(layers "F.Cu" "F.Mask" "F.Paste")
			(net "SMB_BMC_MM16_R1_SDA")
		)
	)
	(footprint ""
		(layer "F.Cu")
		(at 32.70504 -68.504054 90)
		(property "Reference" "R659"
			(at 0 0 90)
			(layer "F.SilkS")
			(hide yes)
			(effects
				(font
					(size 1.27 1.27)
				)
			)
		)
		(property "Value" ""
			(at 0 0 90)
			(layer "F.Fab")
			(effects
				(font
					(size 1.27 1.27)
				)
			)
		)
		(duplicate_pad_numbers_are_jumpers no)
		(fp_line
			(start 0.7874 -0.4064)
			(end 0.7874 0.4064)
			(stroke
				(width 0.1524)
				(type default)
			)
			(layer "F.SilkS")
		)
		(fp_line
			(start -0.7874 -0.4064)
			(end 0.7874 -0.4064)
			(stroke
				(width 0.1524)
				(type default)
			)
			(layer "F.SilkS")
		)
		(fp_line
			(start 0.7874 0.4064)
			(end -0.7874 0.4064)
			(stroke
				(width 0.1524)
				(type default)
			)
			(layer "F.SilkS")
		)
		(fp_line
			(start -0.7874 0.4064)
			(end -0.7874 -0.4064)
			(stroke
				(width 0.1524)
				(type default)
			)
			(layer "F.SilkS")
		)
		(fp_line
			(start -0.12065 -0.305054)
			(end -0.12065 -0.2794)
			(stroke
				(width 0.1)
				(type default)
			)
			(layer "F.Fab")
		)
		(fp_line
			(start -0.67945 -0.305054)
			(end -0.12065 -0.305054)
			(stroke
				(width 0.1)
				(type default)
			)
			(layer "F.Fab")
		)
		(fp_line
			(start 0.67945 -0.3048)
			(end 0.67945 0.3048)
			(stroke
				(width 0.1)
				(type default)
			)
			(layer "F.Fab")
		)
		(fp_line
			(start 0.12065 -0.3048)
			(end 0.67945 -0.3048)
			(stroke
				(width 0.1)
				(type default)
			)
			(layer "F.Fab")
		)
		(fp_line
			(start 0.12065 -0.2794)
			(end 0.12065 -0.3048)
			(stroke
				(width 0.1)
				(type default)
			)
			(layer "F.Fab")
		)
		(fp_line
			(start -0.12065 -0.2794)
			(end 0.12065 -0.2794)
			(stroke
				(width 0.1)
				(type default)
			)
			(layer "F.Fab")
		)
		(fp_line
			(start 0.120396 0.2794)
			(end -0.12065 0.2794)
			(stroke
				(width 0.1)
				(type default)
			)
			(layer "F.Fab")
		)
		(fp_line
			(start -0.12065 0.2794)
			(end -0.12065 0.3048)
			(stroke
				(width 0.1)
				(type default)
			)
			(layer "F.Fab")
		)
		(fp_line
			(start 0.67945 0.3048)
			(end 0.120396 0.3048)
			(stroke
				(width 0.1)
				(type default)
			)
			(layer "F.Fab")
		)
		(fp_line
			(start 0.120396 0.3048)
			(end 0.120396 0.2794)
			(stroke
				(width 0.1)
				(type default)
			)
			(layer "F.Fab")
		)
		(fp_line
			(start -0.12065 0.3048)
			(end -0.67945 0.3048)
			(stroke
				(width 0.1)
				(type default)
			)
			(layer "F.Fab")
		)
		(fp_line
			(start -0.67945 0.3048)
			(end -0.67945 -0.305054)
			(stroke
				(width 0.1)
				(type default)
			)
			(layer "F.Fab")
		)
		(pad "1" smd circle
			(at -0.40005 0 90)
			(size 0 0)
			(layers "F.Cu" "F.Mask" "F.Paste")
			(net "P3V3_AUX")
		)
		(pad "2" smd circle
			(at 0.40005 0 90)
			(size 0 0)
			(layers "F.Cu" "F.Mask" "F.Paste")
			(net "EMMC_DT4_R")
		)
	)
	(footprint ""
		(layer "F.Cu")
		(at 23.495 -102.743 -90)
		(property "Reference" "R579"
			(at 0 0 270)
			(layer "F.SilkS")
			(hide yes)
			(effects
				(font
					(size 1.27 1.27)
				)
			)
		)
		(property "Value" ""
			(at 0 0 270)
			(layer "F.Fab")
			(effects
				(font
					(size 1.27 1.27)
				)
			)
		)
		(duplicate_pad_numbers_are_jumpers no)
		(fp_line
			(start -0.7874 0.4064)
			(end -0.7874 -0.4064)
			(stroke
				(width 0.1524)
				(type default)
			)
			(layer "F.SilkS")
		)
		(fp_line
			(start 0.7874 0.4064)
			(end -0.7874 0.4064)
			(stroke
				(width 0.1524)
				(type default)
			)
			(layer "F.SilkS")
		)
		(fp_line
			(start -0.7874 -0.4064)
			(end 0.7874 -0.4064)
			(stroke
				(width 0.1524)
				(type default)
			)
			(layer "F.SilkS")
		)
		(fp_line
			(start 0.7874 -0.4064)
			(end 0.7874 0.4064)
			(stroke
				(width 0.1524)
				(type default)
			)
			(layer "F.SilkS")
		)
		(fp_line
			(start -0.67945 0.3048)
			(end -0.67945 -0.305054)
			(stroke
				(width 0.1)
				(type default)
			)
			(layer "F.Fab")
		)
		(fp_line
			(start -0.12065 0.3048)
			(end -0.67945 0.3048)
			(stroke
				(width 0.1)
				(type default)
			)
			(layer "F.Fab")
		)
		(fp_line
			(start 0.120396 0.3048)
			(end 0.120396 0.2794)
			(stroke
				(width 0.1)
				(type default)
			)
			(layer "F.Fab")
		)
		(fp_line
			(start 0.67945 0.3048)
			(end 0.120396 0.3048)
			(stroke
				(width 0.1)
				(type default)
			)
			(layer "F.Fab")
		)
		(fp_line
			(start -0.12065 0.2794)
			(end -0.12065 0.3048)
			(stroke
				(width 0.1)
				(type default)
			)
			(layer "F.Fab")
		)
		(fp_line
			(start 0.120396 0.2794)
			(end -0.12065 0.2794)
			(stroke
				(width 0.1)
				(type default)
			)
			(layer "F.Fab")
		)
		(fp_line
			(start -0.12065 -0.2794)
			(end 0.12065 -0.2794)
			(stroke
				(width 0.1)
				(type default)
			)
			(layer "F.Fab")
		)
		(fp_line
			(start 0.12065 -0.2794)
			(end 0.12065 -0.3048)
			(stroke
				(width 0.1)
				(type default)
			)
			(layer "F.Fab")
		)
		(fp_line
			(start 0.12065 -0.3048)
			(end 0.67945 -0.3048)
			(stroke
				(width 0.1)
				(type default)
			)
			(layer "F.Fab")
		)
		(fp_line
			(start 0.67945 -0.3048)
			(end 0.67945 0.3048)
			(stroke
				(width 0.1)
				(type default)
			)
			(layer "F.Fab")
		)
		(fp_line
			(start -0.67945 -0.305054)
			(end -0.12065 -0.305054)
			(stroke
				(width 0.1)
				(type default)
			)
			(layer "F.Fab")
		)
		(fp_line
			(start -0.12065 -0.305054)
			(end -0.12065 -0.2794)
			(stroke
				(width 0.1)
				(type default)
			)
			(layer "F.Fab")
		)
		(pad "1" smd circle
			(at -0.40005 0 270)
			(size 0 0)
			(layers "F.Cu" "F.Mask" "F.Paste")
			(net "FM_DEBUG_PORT_PRSNT_N")
		)
		(pad "2" smd circle
			(at 0.40005 0 270)
			(size 0 0)
			(layers "F.Cu" "F.Mask" "F.Paste")
			(net "FM_DEBUG_PORT_R2_PRSNT_N")
		)
	)
	(footprint ""
		(layer "F.Cu")
		(at 80.4418 -30.8356 -90)
		(property "Reference" "R599"
			(at 0 0 270)
			(layer "F.SilkS")
			(hide yes)
			(effects
				(font
					(size 1.27 1.27)
				)
			)
		)
		(property "Value" ""
			(at 0 0 270)
			(layer "F.Fab")
			(effects
				(font
					(size 1.27 1.27)
				)
			)
		)
		(duplicate_pad_numbers_are_jumpers no)
		(fp_line
			(start -0.7874 0.4064)
			(end -0.7874 -0.4064)
			(stroke
				(width 0.1524)
				(type default)
			)
			(layer "F.SilkS")
		)
		(fp_line
			(start 0.7874 0.4064)
			(end -0.7874 0.4064)
			(stroke
				(width 0.1524)
				(type default)
			)
			(layer "F.SilkS")
		)
		(fp_line
			(start -0.7874 -0.4064)
			(end 0.7874 -0.4064)
			(stroke
				(width 0.1524)
				(type default)
			)
			(layer "F.SilkS")
		)
		(fp_line
			(start 0.7874 -0.4064)
			(end 0.7874 0.4064)
			(stroke
				(width 0.1524)
				(type default)
			)
			(layer "F.SilkS")
		)
		(fp_line
			(start -0.67945 0.3048)
			(end -0.67945 -0.305054)
			(stroke
				(width 0.1)
				(type default)
			)
			(layer "F.Fab")
		)
		(fp_line
			(start -0.12065 0.3048)
			(end -0.67945 0.3048)
			(stroke
				(width 0.1)
				(type default)
			)
			(layer "F.Fab")
		)
		(fp_line
			(start 0.120396 0.3048)
			(end 0.120396 0.2794)
			(stroke
				(width 0.1)
				(type default)
			)
			(layer "F.Fab")
		)
		(fp_line
			(start 0.67945 0.3048)
			(end 0.120396 0.3048)
			(stroke
				(width 0.1)
				(type default)
			)
			(layer "F.Fab")
		)
		(fp_line
			(start -0.12065 0.2794)
			(end -0.12065 0.3048)
			(stroke
				(width 0.1)
				(type default)
			)
			(layer "F.Fab")
		)
		(fp_line
			(start 0.120396 0.2794)
			(end -0.12065 0.2794)
			(stroke
				(width 0.1)
				(type default)
			)
			(layer "F.Fab")
		)
		(fp_line
			(start -0.12065 -0.2794)
			(end 0.12065 -0.2794)
			(stroke
				(width 0.1)
				(type default)
			)
			(layer "F.Fab")
		)
		(fp_line
			(start 0.12065 -0.2794)
			(end 0.12065 -0.3048)
			(stroke
				(width 0.1)
				(type default)
			)
			(layer "F.Fab")
		)
		(fp_line
			(start 0.12065 -0.3048)
			(end 0.67945 -0.3048)
			(stroke
				(width 0.1)
				(type default)
			)
			(layer "F.Fab")
		)
		(fp_line
			(start 0.67945 -0.3048)
			(end 0.67945 0.3048)
			(stroke
				(width 0.1)
				(type default)
			)
			(layer "F.Fab")
		)
		(fp_line
			(start -0.67945 -0.305054)
			(end -0.12065 -0.305054)
			(stroke
				(width 0.1)
				(type default)
			)
			(layer "F.Fab")
		)
		(fp_line
			(start -0.12065 -0.305054)
			(end -0.12065 -0.2794)
			(stroke
				(width 0.1)
				(type default)
			)
			(layer "F.Fab")
		)
		(pad "1" smd circle
			(at -0.40005 0 270)
			(size 0 0)
			(layers "F.Cu" "F.Mask" "F.Paste")
			(net "LED_POSTCODE_5")
		)
		(pad "2" smd circle
			(at 0.40005 0 270)
			(size 0 0)
			(layers "F.Cu" "F.Mask" "F.Paste")
			(net "LED_POSTCODE_5_R")
		)
	)
	(footprint ""
		(layer "F.Cu")
		(at 25.3238 -30.6324 90)
		(property "Reference" "PR205"
			(at 0 0 90)
			(layer "F.SilkS")
			(hide yes)
			(effects
				(font
					(size 1.27 1.27)
				)
			)
		)
		(property "Value" ""
			(at 0 0 90)
			(layer "F.Fab")
			(effects
				(font
					(size 1.27 1.27)
				)
			)
		)
		(duplicate_pad_numbers_are_jumpers no)
		(fp_line
			(start 0.7874 -0.4064)
			(end 0.7874 0.4064)
			(stroke
				(width 0.1524)
				(type default)
			)
			(layer "F.SilkS")
		)
		(fp_line
			(start -0.7874 -0.4064)
			(end 0.7874 -0.4064)
			(stroke
				(width 0.1524)
				(type default)
			)
			(layer "F.SilkS")
		)
		(fp_line
			(start 0.7874 0.4064)
			(end -0.7874 0.4064)
			(stroke
				(width 0.1524)
				(type default)
			)
			(layer "F.SilkS")
		)
		(fp_line
			(start -0.7874 0.4064)
			(end -0.7874 -0.4064)
			(stroke
				(width 0.1524)
				(type default)
			)
			(layer "F.SilkS")
		)
		(fp_line
			(start -0.12065 -0.305054)
			(end -0.12065 -0.2794)
			(stroke
				(width 0.1)
				(type default)
			)
			(layer "F.Fab")
		)
		(fp_line
			(start -0.67945 -0.305054)
			(end -0.12065 -0.305054)
			(stroke
				(width 0.1)
				(type default)
			)
			(layer "F.Fab")
		)
		(fp_line
			(start 0.67945 -0.3048)
			(end 0.67945 0.3048)
			(stroke
				(width 0.1)
				(type default)
			)
			(layer "F.Fab")
		)
		(fp_line
			(start 0.12065 -0.3048)
			(end 0.67945 -0.3048)
			(stroke
				(width 0.1)
				(type default)
			)
			(layer "F.Fab")
		)
		(fp_line
			(start 0.12065 -0.2794)
			(end 0.12065 -0.3048)
			(stroke
				(width 0.1)
				(type default)
			)
			(layer "F.Fab")
		)
		(fp_line
			(start -0.12065 -0.2794)
			(end 0.12065 -0.2794)
			(stroke
				(width 0.1)
				(type default)
			)
			(layer "F.Fab")
		)
		(fp_line
			(start 0.120396 0.2794)
			(end -0.12065 0.2794)
			(stroke
				(width 0.1)
				(type default)
			)
			(layer "F.Fab")
		)
		(fp_line
			(start -0.12065 0.2794)
			(end -0.12065 0.3048)
			(stroke
				(width 0.1)
				(type default)
			)
			(layer "F.Fab")
		)
		(fp_line
			(start 0.67945 0.3048)
			(end 0.120396 0.3048)
			(stroke
				(width 0.1)
				(type default)
			)
			(layer "F.Fab")
		)
		(fp_line
			(start 0.120396 0.3048)
			(end 0.120396 0.2794)
			(stroke
				(width 0.1)
				(type default)
			)
			(layer "F.Fab")
		)
		(fp_line
			(start -0.12065 0.3048)
			(end -0.67945 0.3048)
			(stroke
				(width 0.1)
				(type default)
			)
			(layer "F.Fab")
		)
		(fp_line
			(start -0.67945 0.3048)
			(end -0.67945 -0.305054)
			(stroke
				(width 0.1)
				(type default)
			)
			(layer "F.Fab")
		)
		(pad "1" smd circle
			(at -0.40005 0 90)
			(size 0 0)
			(layers "F.Cu" "F.Mask" "F.Paste")
			(net "P5V_AUX")
		)
		(pad "2" smd circle
			(at 0.40005 0 90)
			(size 0 0)
			(layers "F.Cu" "F.Mask" "F.Paste")
			(net "PVCC2_AUX")
		)
	)
	(footprint ""
		(layer "F.Cu")
		(at 6.100064 -22.690074)
		(property "Reference" "H5"
			(at -5.007864 -0.130556 0)
			(unlocked yes)
			(layer "F.SilkS")
			(effects
				(font
					(size 0.7874 0.5842)
					(thickness 0.1524)
				)
				(justify left)
			)
		)
		(property "Value" ""
			(at 0 0 0)
			(layer "F.Fab")
			(effects
				(font
					(size 1.27 1.27)
				)
			)
		)
		(duplicate_pad_numbers_are_jumpers no)
		(pad "1" thru_hole circle
			(at 0 0)
			(size 6.0452 6.0452)
			(drill 3.1496)
			(layers "*.Cu" "*.Mask")
			(remove_unused_layers no)
			(net "GND")
			(clearance -1.1938)
		)
	)
)
